(kicad_pcb
	(version 20241229)
	(generator "pcbnew")
	(generator_version "9.0")
	(general
		(thickness 1.63)
		(legacy_teardrops no)
	)
	(paper "A4")
	(title_block
		(title "CM4 Baseboard")
		(date "2026-01-05")
		(rev "1.1.1")
		(company "Antmicro Ltd")
		(comment 1 "www.antmicro.com")
		(comment 9 "footprints 449-453 of 506")
	)
	(layers
		(0 "F.Cu" signal)
		(4 "In1.Cu" power)
		(6 "In2.Cu" power)
		(8 "In3.Cu" signal)
		(10 "In4.Cu" signal)
		(2 "B.Cu" signal)
		(9 "F.Adhes" user "F.Adhesive")
		(11 "B.Adhes" user "B.Adhesive")
		(13 "F.Paste" user)
		(15 "B.Paste" user)
		(5 "F.SilkS" user "F.Silkscreen")
		(7 "B.SilkS" user "B.Silkscreen")
		(1 "F.Mask" user)
		(3 "B.Mask" user)
		(17 "Dwgs.User" user "User.Drawings")
		(19 "Cmts.User" user "User.Comments")
		(21 "Eco1.User" user "User.Eco1")
		(23 "Eco2.User" user "User.Eco2")
		(25 "Edge.Cuts" user)
		(27 "Margin" user)
		(31 "F.CrtYd" user "F.Courtyard")
		(29 "B.CrtYd" user "B.Courtyard")
		(35 "F.Fab" user)
		(33 "B.Fab" user)
	)
	(footprint "antmicro-footprints:R_0402_1005Metric"
		(layer "B.Cu")
		(at 76.442962 150.6165)
		(descr "Resistor SMD 0402")
		(tags "resistor SMD 0402")
		(property "Reference" "R224"
			(at -0.892962 -0.5165 0)
			(layer "B.SilkS")
			(effects
				(font
					(size 0.7 0.7)
					(thickness 0.15)
				)
				(justify right bottom mirror)
			)
		)
		(property "Value" "R_1k_0402"
			(at -1.011843 -1.772047 0)
			(layer "B.Fab")
			(effects
				(font
					(size 0.7 0.7)
					(thickness 0.15)
				)
				(justify right bottom mirror)
			)
		)
		(property "Datasheet" "https://www.bourns.com/docs/product-datasheets/cr.pdf"
			(at 0 0 0)
			(layer "B.Fab")
			(hide yes)
			(effects
				(font
					(size 1.27 1.27)
					(thickness 0.15)
				)
			)
		)
		(property "MPN" "CR0402-FX-1001GLF"
			(at 0 0 0)
			(unlocked yes)
			(layer "B.Fab")
			(hide yes)
			(effects
				(font
					(size 1 1)
					(thickness 0.15)
				)
				(justify mirror)
			)
		)
		(property "Manufacturer" "Bourns"
			(at 0 0 0)
			(unlocked yes)
			(layer "B.Fab")
			(hide yes)
			(effects
				(font
					(size 1 1)
					(thickness 0.15)
				)
				(justify mirror)
			)
		)
		(property "License" "Apache-2.0"
			(at 0 0 0)
			(unlocked yes)
			(layer "B.Fab")
			(hide yes)
			(effects
				(font
					(size 1 1)
					(thickness 0.15)
				)
				(justify mirror)
			)
		)
		(property "Author" "Antmicro"
			(at 0 0 0)
			(unlocked yes)
			(layer "B.Fab")
			(hide yes)
			(effects
				(font
					(size 1 1)
					(thickness 0.15)
				)
				(justify mirror)
			)
		)
		(property "Val" "1k"
			(at 0 0 0)
			(unlocked yes)
			(layer "B.Fab")
			(hide yes)
			(effects
				(font
					(size 1 1)
					(thickness 0.15)
				)
				(justify mirror)
			)
		)
		(property "Tolerance" "1%"
			(at 0 0 0)
			(unlocked yes)
			(layer "B.Fab")
			(hide yes)
			(effects
				(font
					(size 1 1)
					(thickness 0.15)
				)
				(justify mirror)
			)
		)
		(sheetname "/Compute module/")
		(sheetfile "compute-module.kicad_sch")
		(attr smd)
		(fp_rect
			(start -0.925 0.47)
			(end 0.925 -0.47)
			(stroke
				(width 0.05)
				(type default)
			)
			(fill no)
			(layer "B.CrtYd")
		)
		(fp_rect
			(start -0.5 0.25)
			(end 0.5 -0.25)
			(stroke
				(width 0.15)
				(type solid)
			)
			(fill no)
			(layer "B.Fab")
		)
		(fp_text user "${REFERENCE}"
			(at -0.95 -3.168 180)
			(layer "B.Fab")
			(effects
				(font
					(size 0.7 0.7)
					(thickness 0.15)
				)
				(justify left bottom mirror)
			)
		)
		(fp_text user "Author: Antmicro"
			(at -0.95 -4.169 180)
			(layer "B.Fab")
			(effects
				(font
					(size 0.7 0.7)
					(thickness 0.15)
				)
				(justify left bottom mirror)
			)
		)
		(fp_text user "License: Apache-2.0"
			(at -0.95 -5.169 180)
			(layer "B.Fab")
			(effects
				(font
					(size 0.7 0.7)
					(thickness 0.15)
				)
				(justify left bottom mirror)
			)
		)
		(pad "1" smd roundrect
			(at -0.48 0)
			(size 0.59 0.64)
			(layers "B.Cu" "B.Mask" "B.Paste")
			(roundrect_rratio 0.25)
			(net 331 "Net-(Q210-D)")
			(pintype "passive")
		)
		(pad "2" smd roundrect
			(at 0.48 0)
			(size 0.59 0.64)
			(layers "B.Cu" "B.Mask" "B.Paste")
			(roundrect_rratio 0.25)
			(net 465 "Net-(D205-C)")
			(pintype "passive")
		)
	)
	(footprint "antmicro-footprints:C_0402_1005Metric"
		(layer "B.Cu")
		(at 75.342962 136.9915 180)
		(descr "Capacitor SMD 0402")
		(tags "capacitor SMD 0402")
		(property "Reference" "C909"
			(at 0.945 -0.375 0)
			(layer "B.SilkS")
			(effects
				(font
					(size 0.7 0.7)
					(thickness 0.15)
				)
				(justify left bottom mirror)
			)
		)
		(property "Value" "C_100n_0402"
			(at -1.022927 -2.155213 0)
			(layer "B.Fab")
			(effects
				(font
					(size 0.7 0.7)
					(thickness 0.15)
				)
				(justify left bottom mirror)
			)
		)
		(property "Datasheet" "https://www.murata.com/products/productdetail?partno=GRM155R61H104KE14%23"
			(at 0 0 180)
			(layer "B.Fab")
			(hide yes)
			(effects
				(font
					(size 1.27 1.27)
					(thickness 0.15)
				)
			)
		)
		(property "Manufacturer" "Murata"
			(at 0 0 180)
			(unlocked yes)
			(layer "B.Fab")
			(hide yes)
			(effects
				(font
					(size 1 1)
					(thickness 0.15)
				)
				(justify mirror)
			)
		)
		(property "MPN" "GRM155R61H104KE14D"
			(at 0 0 180)
			(unlocked yes)
			(layer "B.Fab")
			(hide yes)
			(effects
				(font
					(size 1 1)
					(thickness 0.15)
				)
				(justify mirror)
			)
		)
		(property "Val" "100n"
			(at 0 0 180)
			(unlocked yes)
			(layer "B.Fab")
			(hide yes)
			(effects
				(font
					(size 1 1)
					(thickness 0.15)
				)
				(justify mirror)
			)
		)
		(property "License" "Apache-2.0"
			(at 0 0 180)
			(unlocked yes)
			(layer "B.Fab")
			(hide yes)
			(effects
				(font
					(size 1 1)
					(thickness 0.15)
				)
				(justify mirror)
			)
		)
		(property "Author" "Antmicro"
			(at 0 0 180)
			(unlocked yes)
			(layer "B.Fab")
			(hide yes)
			(effects
				(font
					(size 1 1)
					(thickness 0.15)
				)
				(justify mirror)
			)
		)
		(property "Voltage" "50V"
			(at 0 0 180)
			(unlocked yes)
			(layer "B.Fab")
			(hide yes)
			(effects
				(font
					(size 1 1)
					(thickness 0.15)
				)
				(justify mirror)
			)
		)
		(property "Dielectric" "X5R"
			(at 0 0 180)
			(unlocked yes)
			(layer "B.Fab")
			(hide yes)
			(effects
				(font
					(size 1 1)
					(thickness 0.15)
				)
				(justify mirror)
			)
		)
		(sheetname "/USB/")
		(sheetfile "usb.kicad_sch")
		(attr smd)
		(fp_rect
			(start -0.925 0.47)
			(end 0.925 -0.47)
			(stroke
				(width 0.05)
				(type default)
			)
			(fill no)
			(layer "B.CrtYd")
		)
		(fp_line
			(start 0.504 0.25)
			(end 0.504 -0.248)
			(stroke
				(width 0.15)
				(type solid)
			)
			(layer "B.Fab")
		)
		(fp_line
			(start 0.504 -0.248)
			(end -0.494 -0.248)
			(stroke
				(width 0.15)
				(type solid)
			)
			(layer "B.Fab")
		)
		(fp_line
			(start -0.494 0.25)
			(end 0.504 0.25)
			(stroke
				(width 0.15)
				(type solid)
			)
			(layer "B.Fab")
		)
		(fp_line
			(start -0.494 -0.248)
			(end -0.494 0.25)
			(stroke
				(width 0.15)
				(type solid)
			)
			(layer "B.Fab")
		)
		(fp_text user "License: Apache-2.0"
			(at -0.939 -5.799 0)
			(layer "B.Fab")
			(effects
				(font
					(size 0.7 0.7)
					(thickness 0.15)
				)
				(justify left bottom mirror)
			)
		)
		(fp_text user "${REFERENCE}"
			(at -0.939 -4.599 0)
			(layer "B.Fab")
			(effects
				(font
					(size 0.7 0.7)
					(thickness 0.15)
				)
				(justify left bottom mirror)
			)
		)
		(fp_text user "Author: Antmicro"
			(at -0.939 -3.399 0)
			(layer "B.Fab")
			(effects
				(font
					(size 0.7 0.7)
					(thickness 0.15)
				)
				(justify left bottom mirror)
			)
		)
		(pad "1" smd roundrect
			(at -0.48 0 180)
			(size 0.59 0.64)
			(layers "B.Cu" "B.Mask" "B.Paste")
			(roundrect_rratio 0.25)
			(net 29 "/USB/USBD_SVBUS")
			(pintype "passive")
		)
		(pad "2" smd roundrect
			(at 0.48 0 180)
			(size 0.59 0.64)
			(layers "B.Cu" "B.Mask" "B.Paste")
			(roundrect_rratio 0.25)
			(net 3 "GND")
			(pintype "passive")
		)
	)
	(footprint "antmicro-footprints:R_0402_1005Metric"
		(layer "B.Cu")
		(at 90.387962 154.3665)
		(descr "Resistor SMD 0402")
		(tags "resistor SMD 0402")
		(property "Reference" "R231"
			(at -1.71 3.94 0)
			(layer "B.SilkS")
			(effects
				(font
					(size 0.7 0.7)
					(thickness 0.15)
				)
				(justify right bottom mirror)
			)
		)
		(property "Value" "R_10k_0402"
			(at -1.011843 -1.772047 0)
			(layer "B.Fab")
			(effects
				(font
					(size 0.7 0.7)
					(thickness 0.15)
				)
				(justify right bottom mirror)
			)
		)
		(property "Datasheet" "https://www.bourns.com/docs/product-datasheets/cr.pdf"
			(at 0 0 0)
			(layer "B.Fab")
			(hide yes)
			(effects
				(font
					(size 1.27 1.27)
					(thickness 0.15)
				)
			)
		)
		(property "MPN" "CR0402-FX-1002GLF"
			(at 0 0 0)
			(unlocked yes)
			(layer "B.Fab")
			(hide yes)
			(effects
				(font
					(size 1 1)
					(thickness 0.15)
				)
				(justify mirror)
			)
		)
		(property "Manufacturer" "Bourns"
			(at 0 0 0)
			(unlocked yes)
			(layer "B.Fab")
			(hide yes)
			(effects
				(font
					(size 1 1)
					(thickness 0.15)
				)
				(justify mirror)
			)
		)
		(property "License" "Apache-2.0"
			(at 0 0 0)
			(unlocked yes)
			(layer "B.Fab")
			(hide yes)
			(effects
				(font
					(size 1 1)
					(thickness 0.15)
				)
				(justify mirror)
			)
		)
		(property "Author" "Antmicro"
			(at 0 0 0)
			(unlocked yes)
			(layer "B.Fab")
			(hide yes)
			(effects
				(font
					(size 1 1)
					(thickness 0.15)
				)
				(justify mirror)
			)
		)
		(property "Val" "10k"
			(at 0 0 0)
			(unlocked yes)
			(layer "B.Fab")
			(hide yes)
			(effects
				(font
					(size 1 1)
					(thickness 0.15)
				)
				(justify mirror)
			)
		)
		(property "Tolerance" "1%"
			(at 0 0 0)
			(unlocked yes)
			(layer "B.Fab")
			(hide yes)
			(effects
				(font
					(size 1 1)
					(thickness 0.15)
				)
				(justify mirror)
			)
		)
		(sheetname "/Compute module/")
		(sheetfile "compute-module.kicad_sch")
		(attr smd)
		(fp_rect
			(start -0.925 0.47)
			(end 0.925 -0.47)
			(stroke
				(width 0.05)
				(type default)
			)
			(fill no)
			(layer "B.CrtYd")
		)
		(fp_rect
			(start -0.5 0.25)
			(end 0.5 -0.25)
			(stroke
				(width 0.15)
				(type solid)
			)
			(fill no)
			(layer "B.Fab")
		)
		(fp_text user "License: Apache-2.0"
			(at -0.95 -5.169 180)
			(layer "B.Fab")
			(effects
				(font
					(size 0.7 0.7)
					(thickness 0.15)
				)
				(justify left bottom mirror)
			)
		)
		(fp_text user "${REFERENCE}"
			(at -0.95 -3.168 180)
			(layer "B.Fab")
			(effects
				(font
					(size 0.7 0.7)
					(thickness 0.15)
				)
				(justify left bottom mirror)
			)
		)
		(fp_text user "Author: Antmicro"
			(at -0.95 -4.169 180)
			(layer "B.Fab")
			(effects
				(font
					(size 0.7 0.7)
					(thickness 0.15)
				)
				(justify left bottom mirror)
			)
		)
		(pad "1" smd roundrect
			(at -0.48 0)
			(size 0.59 0.64)
			(layers "B.Cu" "B.Mask" "B.Paste")
			(roundrect_rratio 0.25)
			(net 3 "GND")
			(pintype "passive")
		)
		(pad "2" smd roundrect
			(at 0.48 0)
			(size 0.59 0.64)
			(layers "B.Cu" "B.Mask" "B.Paste")
			(roundrect_rratio 0.25)
			(net 345 "Net-(U204-A2)")
			(pintype "passive")
		)
	)
	(footprint "antmicro-footprints:C_0402_1005Metric"
		(layer "B.Cu")
		(at 119.142962 132.3165 -90)
		(descr "Capacitor SMD 0402")
		(tags "capacitor SMD 0402")
		(property "Reference" "C501"
			(at -1.31 0.575 90)
			(layer "B.SilkS")
			(effects
				(font
					(size 0.7 0.7)
					(thickness 0.15)
				)
				(justify left bottom mirror)
			)
		)
		(property "Value" "C_10u_0402"
			(at -1.022927 -2.155213 90)
			(layer "B.Fab")
			(effects
				(font
					(size 0.7 0.7)
					(thickness 0.15)
				)
				(justify left bottom mirror)
			)
		)
		(property "Datasheet" "https://www.yageo.com/en/Chart/Download/pdf/CC0402MRX5R5BB106"
			(at 0 0 270)
			(layer "B.Fab")
			(hide yes)
			(effects
				(font
					(size 1.27 1.27)
					(thickness 0.15)
				)
			)
		)
		(property "MPN" "CC0402MRX5R5BB106"
			(at 0 0 270)
			(unlocked yes)
			(layer "B.Fab")
			(hide yes)
			(effects
				(font
					(size 1 1)
					(thickness 0.15)
				)
				(justify mirror)
			)
		)
		(property "Manufacturer" "YAGEO"
			(at 0 0 270)
			(unlocked yes)
			(layer "B.Fab")
			(hide yes)
			(effects
				(font
					(size 1 1)
					(thickness 0.15)
				)
				(justify mirror)
			)
		)
		(property "License" "Apache-2.0"
			(at 0 0 270)
			(unlocked yes)
			(layer "B.Fab")
			(hide yes)
			(effects
				(font
					(size 1 1)
					(thickness 0.15)
				)
				(justify mirror)
			)
		)
		(property "Author" "Antmicro"
			(at 0 0 270)
			(unlocked yes)
			(layer "B.Fab")
			(hide yes)
			(effects
				(font
					(size 1 1)
					(thickness 0.15)
				)
				(justify mirror)
			)
		)
		(property "Val" "10u"
			(at 0 0 270)
			(unlocked yes)
			(layer "B.Fab")
			(hide yes)
			(effects
				(font
					(size 1 1)
					(thickness 0.15)
				)
				(justify mirror)
			)
		)
		(property "Voltage" ""
			(at 0 0 270)
			(unlocked yes)
			(layer "B.Fab")
			(hide yes)
			(effects
				(font
					(size 1 1)
					(thickness 0.15)
				)
				(justify mirror)
			)
		)
		(property "Dielectric" ""
			(at 0 0 270)
			(unlocked yes)
			(layer "B.Fab")
			(hide yes)
			(effects
				(font
					(size 1 1)
					(thickness 0.15)
				)
				(justify mirror)
			)
		)
		(sheetname "/NVMe & microSD/")
		(sheetfile "nvme-micro-sd.kicad_sch")
		(attr smd)
		(fp_rect
			(start -0.925 0.47)
			(end 0.925 -0.47)
			(stroke
				(width 0.05)
				(type default)
			)
			(fill no)
			(layer "B.CrtYd")
		)
		(fp_line
			(start -0.494 0.25)
			(end 0.504 0.25)
			(stroke
				(width 0.15)
				(type solid)
			)
			(layer "B.Fab")
		)
		(fp_line
			(start 0.504 0.25)
			(end 0.504 -0.248)
			(stroke
				(width 0.15)
				(type solid)
			)
			(layer "B.Fab")
		)
		(fp_line
			(start -0.494 -0.248)
			(end -0.494 0.25)
			(stroke
				(width 0.15)
				(type solid)
			)
			(layer "B.Fab")
		)
		(fp_line
			(start 0.504 -0.248)
			(end -0.494 -0.248)
			(stroke
				(width 0.15)
				(type solid)
			)
			(layer "B.Fab")
		)
		(fp_text user "${REFERENCE}"
			(at -0.939 -4.599 90)
			(layer "B.Fab")
			(effects
				(font
					(size 0.7 0.7)
					(thickness 0.15)
				)
				(justify left bottom mirror)
			)
		)
		(fp_text user "Author: Antmicro"
			(at -0.939 -3.399 90)
			(layer "B.Fab")
			(effects
				(font
					(size 0.7 0.7)
					(thickness 0.15)
				)
				(justify left bottom mirror)
			)
		)
		(fp_text user "License: Apache-2.0"
			(at -0.939 -5.799 90)
			(layer "B.Fab")
			(effects
				(font
					(size 0.7 0.7)
					(thickness 0.15)
				)
				(justify left bottom mirror)
			)
		)
		(pad "1" smd roundrect
			(at -0.48 0 270)
			(size 0.59 0.64)
			(layers "B.Cu" "B.Mask" "B.Paste")
			(roundrect_rratio 0.25)
			(net 3 "GND")
			(pintype "passive")
		)
		(pad "2" smd roundrect
			(at 0.48 0 270)
			(size 0.59 0.64)
			(layers "B.Cu" "B.Mask" "B.Paste")
			(roundrect_rratio 0.25)
			(net 65 "3V3_SSD")
			(pintype "passive")
		)
	)
	(footprint "antmicro-footprints:TSOT23-6"
		(layer "B.Cu")
		(at 66.162962 163.7465 90)
		(property "Reference" "U302"
			(at -4.71 0.065 90)
			(layer "B.SilkS")
			(effects
				(font
					(size 0.7 0.7)
					(thickness 0.15)
				)
				(justify right bottom mirror)
			)
		)
		(property "Value" "AP62301_TSOT"
			(at 0 -2.6 90)
			(layer "B.Fab")
			(effects
				(font
					(size 0.7 0.7)
					(thickness 0.15)
				)
				(justify right bottom mirror)
			)
		)
		(property "Datasheet" "https://www.diodes.com/assets/Datasheets/AP62300_AP62301_AP62300T.pdf"
			(at 0 0 90)
			(layer "B.Fab")
			(hide yes)
			(effects
				(font
					(size 1.27 1.27)
					(thickness 0.15)
				)
			)
		)
		(property "MPN" "AP62301WU-7"
			(at 0 0 90)
			(unlocked yes)
			(layer "B.Fab")
			(hide yes)
			(effects
				(font
					(size 1 1)
					(thickness 0.15)
				)
				(justify mirror)
			)
		)
		(property "Manufacturer" "Diodes Incorporated"
			(at 0 0 90)
			(unlocked yes)
			(layer "B.Fab")
			(hide yes)
			(effects
				(font
					(size 1 1)
					(thickness 0.15)
				)
				(justify mirror)
			)
		)
		(property "Author" "Antmicro"
			(at 0 0 90)
			(unlocked yes)
			(layer "B.Fab")
			(hide yes)
			(effects
				(font
					(size 1 1)
					(thickness 0.15)
				)
				(justify mirror)
			)
		)
		(property "License" "Apache-2.0"
			(at 0 0 90)
			(unlocked yes)
			(layer "B.Fab")
			(hide yes)
			(effects
				(font
					(size 1 1)
					(thickness 0.15)
				)
				(justify mirror)
			)
		)
		(sheetname "/Supply/")
		(sheetfile "supply.kicad_sch")
		(attr smd)
		(fp_line
			(start 1 -1.55)
			(end -1 -1.55)
			(stroke
				(width 0.15)
				(type solid)
			)
			(layer "B.SilkS")
		)
		(fp_line
			(start 1 -1.55)
			(end 1 -1.4)
			(stroke
				(width 0.15)
				(type solid)
			)
			(layer "B.SilkS")
		)
		(fp_line
			(start -1 -1.55)
			(end -1 -1.4)
			(stroke
				(width 0.15)
				(type solid)
			)
			(layer "B.SilkS")
		)
		(fp_line
			(start 1 1.497)
			(end 1 1.375)
			(stroke
				(width 0.15)
				(type solid)
			)
			(layer "B.SilkS")
		)
		(fp_line
			(start 1 1.497)
			(end -1 1.5)
			(stroke
				(width 0.15)
				(type solid)
			)
			(layer "B.SilkS")
		)
		(fp_line
			(start -1 1.5)
			(end -1 1.375)
			(stroke
				(width 0.15)
				(type solid)
			)
			(layer "B.SilkS")
		)
		(fp_circle
			(center -1.44 1.5)
			(end -1.39 1.5)
			(stroke
				(width 0.15)
				(type solid)
			)
			(fill yes)
			(layer "B.SilkS")
		)
		(fp_rect
			(start 1.93 1.7)
			(end -1.93 -1.7)
			(stroke
				(width 0.05)
				(type solid)
			)
			(fill no)
			(layer "B.CrtYd")
		)
		(fp_line
			(start -0.45 1.521)
			(end -0.876 1.096)
			(stroke
				(width 0.15)
				(type solid)
			)
			(layer "B.Fab")
		)
		(fp_rect
			(start 0.875 -1.528)
			(end -0.875 1.525)
			(stroke
				(width 0.15)
				(type solid)
			)
			(fill no)
			(layer "B.Fab")
		)
		(fp_text user "License: Apache-2.0"
			(at -1.93 -6.199 270)
			(layer "B.Fab")
			(effects
				(font
					(size 0.7 0.7)
					(thickness 0.15)
				)
				(justify left bottom mirror)
			)
		)
		(fp_text user "Author: Antmicro"
			(at -1.93 -5 270)
			(layer "B.Fab")
			(effects
				(font
					(size 0.7 0.7)
					(thickness 0.15)
				)
				(justify left bottom mirror)
			)
		)
		(fp_text user "${REFERENCE}"
			(at -1.93 -3.8 270)
			(layer "B.Fab")
			(effects
				(font
					(size 0.7 0.7)
					(thickness 0.15)
				)
				(justify left bottom mirror)
			)
		)
		(pad "1" smd rect
			(at -1.301 0.947 180)
			(size 0.7 1.2)
			(layers "B.Cu" "B.Mask" "B.Paste")
			(net 3 "GND")
			(pinfunction "GND")
			(pintype "power_in")
		)
		(pad "2" smd rect
			(at -1.301 -0.004 180)
			(size 0.7 1.2)
			(layers "B.Cu" "B.Mask" "B.Paste")
			(net 49 "/Supply/SW_3V3")
			(pinfunction "SW")
			(pintype "power_out")
		)
		(pad "3" smd rect
			(at -1.301 -0.954 180)
			(size 0.7 1.2)
			(layers "B.Cu" "B.Mask" "B.Paste")
			(net 43 "VCC")
			(pinfunction "VIN")
			(pintype "power_in")
		)
		(pad "4" smd rect
			(at 1.299 -0.954 180)
			(size 0.7 1.2)
			(layers "B.Cu" "B.Mask" "B.Paste")
			(net 355 "/Supply/FB_3V3")
			(pinfunction "FB")
			(pintype "input")
		)
		(pad "5" smd rect
			(at 1.299 -0.004 180)
			(size 0.7 1.2)
			(layers "B.Cu" "B.Mask" "B.Paste")
			(net 350 "/Supply/EN_3V3")
			(pinfunction "EN")
			(pintype "input")
		)
		(pad "6" smd rect
			(at 1.299 0.947 180)
			(size 0.7 1.2)
			(layers "B.Cu" "B.Mask" "B.Paste")
			(net 51 "Net-(U302-BST)")
			(pinfunction "BST")
			(pintype "output")
		)
	)
)
